# T6G (Grand Teton) — schematic netlist excerpt (pin names and nets, part order shuffled) for the footprints in the layout excerpt that follows; sources: Cadence DE-HDL packaged netlist, KiCad conversion of 04192023_DAF0TMB3IC0_F0TG_MB_C_brd_V02_OCP.brd

C994  Q_CAP  10UF 6.3V 20% X6S  pkg C0402  page 312 : A = P1V8_CPU0_RT_1D ; B = GND
R3237  Q_RES  0 5% CHIP  pkg 0402LF  page 132 : A = OCP_SFF_RBT_ARB_OUT ; B = OCP_SFF_RBT_ARB_IN_R
R1076  Q_RES  4.7K 5% CHIP  pkg 0201LF  page 298 : A = TEST1_RT_CPU0_P2 ; B = GND

(kicad_pcb
	(version 20260206)
	(generator "pcbnew")
	(generator_version "10.0")
	(general
		(thickness 1.6)
		(legacy_teardrops no)
	)
	(paper "A4")
	(title_block
		(title "04192023_DAF0TMB3IC0_F0TG_MB_C_brd_V02_OCP.brd")
		(comment 1 "Grand Teton / footprints 5834-5836 of 8354")
	)
	(layers
		(0 "F.Cu" signal "TOP")
		(4 "In1.Cu" signal "GND")
		(6 "In2.Cu" signal "IN1")
		(8 "In3.Cu" signal "GND1")
		(10 "In4.Cu" signal "IN2")
		(12 "In5.Cu" signal "GND2")
		(14 "In6.Cu" signal "IN3")
		(16 "In7.Cu" signal "GND3")
		(18 "In8.Cu" signal "VCC")
		(20 "In9.Cu" signal "VCC1")
		(22 "In10.Cu" signal "GND4")
		(24 "In11.Cu" signal "IN4")
		(26 "In12.Cu" signal "GND5")
		(28 "In13.Cu" signal "IN5")
		(30 "In14.Cu" signal "GND6")
		(32 "In15.Cu" signal "IN6")
		(34 "In16.Cu" signal "GND7")
		(2 "B.Cu" signal "BOTTOM")
		(9 "F.Adhes" user "F.Adhesive")
		(11 "B.Adhes" user "B.Adhesive")
		(13 "F.Paste" user "Package Geometry/Pastemask Top")
		(15 "B.Paste" user "Package Geometry/Pastemask Bottom")
		(5 "F.SilkS" user "Ref Des/Silkscreen Top")
		(7 "B.SilkS" user "Ref Des/Silkscreen Bottom")
		(1 "F.Mask" user "Board Geometry/Soldermask Top")
		(3 "B.Mask" user "Board Geometry/Soldermask Bottom")
		(17 "Dwgs.User" user "User.Drawings")
		(19 "Cmts.User" user "User.Comments")
		(21 "Eco1.User" user "User.Eco1")
		(23 "Eco2.User" user "User.Eco2")
		(25 "Edge.Cuts" user "Board Geometry/Outline")
		(27 "Margin" user)
		(31 "F.CrtYd" user "Package Geometry/Place Bound Top")
		(29 "B.CrtYd" user "Package Geometry/Place Bound Bottom")
		(35 "F.Fab" user "Ref Des/Assembly Top")
		(33 "B.Fab" user "Ref Des/Assembly Bottom")
	)
	(footprint ""
		(layer "B.Cu")
		(at 398.893538 -393.04468 180)
		(property "Reference" "R1076"
			(at 0 0 0)
			(layer "B.SilkS")
			(hide yes)
			(effects
				(font
					(size 1.27 1.27)
				)
				(justify mirror)
			)
		)
		(property "Value" ""
			(at 0 0 0)
			(layer "B.Fab")
			(effects
				(font
					(size 1.27 1.27)
				)
				(justify mirror)
			)
		)
		(duplicate_pad_numbers_are_jumpers no)
		(fp_line
			(start 0.32512 0.175006)
			(end 0.32512 -0.175006)
			(stroke
				(width 0.1)
				(type default)
			)
			(layer "B.Fab")
		)
		(fp_line
			(start 0.32512 -0.175006)
			(end -0.32512 -0.175006)
			(stroke
				(width 0.1)
				(type default)
			)
			(layer "B.Fab")
		)
		(fp_line
			(start -0.32512 0.175006)
			(end 0.32512 0.175006)
			(stroke
				(width 0.1)
				(type default)
			)
			(layer "B.Fab")
		)
		(fp_line
			(start -0.32512 -0.175006)
			(end -0.32512 0.175006)
			(stroke
				(width 0.1)
				(type default)
			)
			(layer "B.Fab")
		)
		(pad "1" smd rect
			(at 0.2667 0)
			(size 0.3048 0.381)
			(layers "B.Cu" "B.Mask" "B.Paste")
			(net "TEST1_RT_CPU0_P2")
		)
		(pad "2" smd rect
			(at -0.2667 0 180)
			(size 0.3048 0.381)
			(layers "B.Cu" "B.Mask" "B.Paste")
			(net "GND")
		)
	)
	(footprint ""
		(layer "B.Cu")
		(at 396.168372 -395.127988 -90)
		(property "Reference" "C994"
			(at 0 0 90)
			(layer "B.SilkS")
			(hide yes)
			(effects
				(font
					(size 1.27 1.27)
				)
				(justify mirror)
			)
		)
		(property "Value" ""
			(at 0 0 90)
			(layer "B.Fab")
			(effects
				(font
					(size 1.27 1.27)
				)
				(justify mirror)
			)
		)
		(duplicate_pad_numbers_are_jumpers no)
		(fp_line
			(start -0.7874 0.4064)
			(end 0.7874 0.4064)
			(stroke
				(width 0.1524)
				(type default)
			)
			(layer "B.SilkS")
		)
		(fp_line
			(start 0.7874 0.4064)
			(end 0.7874 -0.4064)
			(stroke
				(width 0.1524)
				(type default)
			)
			(layer "B.SilkS")
		)
		(fp_line
			(start -0.7874 -0.4064)
			(end -0.7874 0.4064)
			(stroke
				(width 0.1524)
				(type default)
			)
			(layer "B.SilkS")
		)
		(fp_line
			(start 0.7874 -0.4064)
			(end -0.7874 -0.4064)
			(stroke
				(width 0.1524)
				(type default)
			)
			(layer "B.SilkS")
		)
		(fp_line
			(start -0.67945 0.3048)
			(end -0.120396 0.3048)
			(stroke
				(width 0.1)
				(type default)
			)
			(layer "B.Fab")
		)
		(fp_line
			(start -0.120396 0.3048)
			(end -0.120396 0.2794)
			(stroke
				(width 0.1)
				(type default)
			)
			(layer "B.Fab")
		)
		(fp_line
			(start 0.12065 0.3048)
			(end 0.67945 0.3048)
			(stroke
				(width 0.1)
				(type default)
			)
			(layer "B.Fab")
		)
		(fp_line
			(start 0.67945 0.3048)
			(end 0.67945 -0.305054)
			(stroke
				(width 0.1)
				(type default)
			)
			(layer "B.Fab")
		)
		(fp_line
			(start -0.120396 0.2794)
			(end 0.12065 0.2794)
			(stroke
				(width 0.1)
				(type default)
			)
			(layer "B.Fab")
		)
		(fp_line
			(start 0.12065 0.2794)
			(end 0.12065 0.3048)
			(stroke
				(width 0.1)
				(type default)
			)
			(layer "B.Fab")
		)
		(fp_line
			(start -0.12065 -0.2794)
			(end -0.12065 -0.3048)
			(stroke
				(width 0.1)
				(type default)
			)
			(layer "B.Fab")
		)
		(fp_line
			(start 0.12065 -0.2794)
			(end -0.12065 -0.2794)
			(stroke
				(width 0.1)
				(type default)
			)
			(layer "B.Fab")
		)
		(fp_line
			(start -0.67945 -0.3048)
			(end -0.67945 0.3048)
			(stroke
				(width 0.1)
				(type default)
			)
			(layer "B.Fab")
		)
		(fp_line
			(start -0.12065 -0.3048)
			(end -0.67945 -0.3048)
			(stroke
				(width 0.1)
				(type default)
			)
			(layer "B.Fab")
		)
		(fp_line
			(start 0.12065 -0.305054)
			(end 0.12065 -0.2794)
			(stroke
				(width 0.1)
				(type default)
			)
			(layer "B.Fab")
		)
		(fp_line
			(start 0.67945 -0.305054)
			(end 0.12065 -0.305054)
			(stroke
				(width 0.1)
				(type default)
			)
			(layer "B.Fab")
		)
		(pad "1" smd circle
			(at 0.40005 0 90)
			(size 0 0)
			(layers "B.Cu" "B.Mask" "B.Paste")
			(net "P1V8_CPU0_RT_1D")
		)
		(pad "2" smd circle
			(at -0.40005 0 90)
			(size 0 0)
			(layers "B.Cu" "B.Mask" "B.Paste")
			(net "GND")
		)
	)
	(footprint ""
		(layer "B.Cu")
		(at 191.271144 -77.27823 -90)
		(property "Reference" "R3237"
			(at 0 0 90)
			(layer "B.SilkS")
			(hide yes)
			(effects
				(font
					(size 1.27 1.27)
				)
				(justify mirror)
			)
		)
		(property "Value" ""
			(at 0 0 90)
			(layer "B.Fab")
			(effects
				(font
					(size 1.27 1.27)
				)
				(justify mirror)
			)
		)
		(duplicate_pad_numbers_are_jumpers no)
		(fp_line
			(start -0.7874 0.4064)
			(end 0.7874 0.4064)
			(stroke
				(width 0.1524)
				(type default)
			)
			(layer "B.SilkS")
		)
		(fp_line
			(start 0.7874 0.4064)
			(end 0.7874 -0.4064)
			(stroke
				(width 0.1524)
				(type default)
			)
			(layer "B.SilkS")
		)
		(fp_line
			(start -0.7874 -0.4064)
			(end -0.7874 0.4064)
			(stroke
				(width 0.1524)
				(type default)
			)
			(layer "B.SilkS")
		)
		(fp_line
			(start 0.7874 -0.4064)
			(end -0.7874 -0.4064)
			(stroke
				(width 0.1524)
				(type default)
			)
			(layer "B.SilkS")
		)
		(fp_line
			(start -0.67945 0.3048)
			(end -0.120396 0.3048)
			(stroke
				(width 0.1)
				(type default)
			)
			(layer "B.Fab")
		)
		(fp_line
			(start -0.120396 0.3048)
			(end -0.120396 0.2794)
			(stroke
				(width 0.1)
				(type default)
			)
			(layer "B.Fab")
		)
		(fp_line
			(start 0.12065 0.3048)
			(end 0.67945 0.3048)
			(stroke
				(width 0.1)
				(type default)
			)
			(layer "B.Fab")
		)
		(fp_line
			(start 0.67945 0.3048)
			(end 0.67945 -0.305054)
			(stroke
				(width 0.1)
				(type default)
			)
			(layer "B.Fab")
		)
		(fp_line
			(start -0.120396 0.2794)
			(end 0.12065 0.2794)
			(stroke
				(width 0.1)
				(type default)
			)
			(layer "B.Fab")
		)
		(fp_line
			(start 0.12065 0.2794)
			(end 0.12065 0.3048)
			(stroke
				(width 0.1)
				(type default)
			)
			(layer "B.Fab")
		)
		(fp_line
			(start -0.12065 -0.2794)
			(end -0.12065 -0.3048)
			(stroke
				(width 0.1)
				(type default)
			)
			(layer "B.Fab")
		)
		(fp_line
			(start 0.12065 -0.2794)
			(end -0.12065 -0.2794)
			(stroke
				(width 0.1)
				(type default)
			)
			(layer "B.Fab")
		)
		(fp_line
			(start -0.67945 -0.3048)
			(end -0.67945 0.3048)
			(stroke
				(width 0.1)
				(type default)
			)
			(layer "B.Fab")
		)
		(fp_line
			(start -0.12065 -0.3048)
			(end -0.67945 -0.3048)
			(stroke
				(width 0.1)
				(type default)
			)
			(layer "B.Fab")
		)
		(fp_line
			(start 0.12065 -0.305054)
			(end 0.12065 -0.2794)
			(stroke
				(width 0.1)
				(type default)
			)
			(layer "B.Fab")
		)
		(fp_line
			(start 0.67945 -0.305054)
			(end 0.12065 -0.305054)
			(stroke
				(width 0.1)
				(type default)
			)
			(layer "B.Fab")
		)
		(pad "1" smd circle
			(at 0.40005 0 90)
			(size 0 0)
			(layers "B.Cu" "B.Mask" "B.Paste")
			(net "OCP_SFF_RBT_ARB_OUT")
		)
		(pad "2" smd circle
			(at -0.40005 0 90)
			(size 0 0)
			(layers "B.Cu" "B.Mask" "B.Paste")
			(net "OCP_SFF_RBT_ARB_IN_R")
		)
	)
)
